# S9S_MB_2U (Grand Teton) — schematic netlist excerpt (pin names and nets, part order shuffled) for the footprints in the layout excerpt that follows; sources: Cadence DE-HDL packaged netlist, KiCad conversion of 03242023_DA0F0TMBIJ0_F0T_Motherboard_J_brd_V01_OCP.brd

U192  LTC4307CMS8  IC  pkg MSOP8  page 245
  ENABLE  = FM_MB_PDB_SMB9_R_EN
  SCL_OUT  = SMB_FAN_3V3AUX_BUF_SCL
  SCL_IN  = SMB_FAN_3V3AUX_R_SCL
  GND  = GND
  READY  = NC
  SDA_IN  = SMB_FAN_3V3AUX_R_SDA
  SDA_OUT  = SMB_FAN_3V3AUX_BUF_SDA
  VCC  = P3V3_AUX

R2994  Q_RES  0 5% CHIP  pkg 0402LF  page 240 : A = P3V_BAT_R1 ; B = P3V_BAT_R

(kicad_pcb
	(version 20260206)
	(generator "pcbnew")
	(generator_version "10.0")
	(general
		(thickness 1.6)
		(legacy_teardrops no)
	)
	(paper "A4")
	(title_block
		(title "03242023_DA0F0TMBIJ0_F0T_Motherboard_J_brd_V01_OCP.brd")
		(comment 1 "Grand Teton / footprints 3906-3907 of 6105")
	)
	(layers
		(0 "F.Cu" signal "TOP")
		(4 "In1.Cu" signal "GND")
		(6 "In2.Cu" signal "IN1")
		(8 "In3.Cu" signal "GND1")
		(10 "In4.Cu" signal "IN2")
		(12 "In5.Cu" signal "GND2")
		(14 "In6.Cu" signal "IN3")
		(16 "In7.Cu" signal "GND3")
		(18 "In8.Cu" signal "VCC")
		(20 "In9.Cu" signal "VCC1")
		(22 "In10.Cu" signal "GND4")
		(24 "In11.Cu" signal "IN4")
		(26 "In12.Cu" signal "GND5")
		(28 "In13.Cu" signal "IN5")
		(30 "In14.Cu" signal "GND6")
		(32 "In15.Cu" signal "IN6")
		(34 "In16.Cu" signal "GND7")
		(2 "B.Cu" signal "BOTTOM")
		(9 "F.Adhes" user "F.Adhesive")
		(11 "B.Adhes" user "B.Adhesive")
		(13 "F.Paste" user "Package Geometry/Pastemask Top")
		(15 "B.Paste" user "Package Geometry/Pastemask Bottom")
		(5 "F.SilkS" user "Ref Des/Silkscreen Top")
		(7 "B.SilkS" user "Ref Des/Silkscreen Bottom")
		(1 "F.Mask" user "Board Geometry/Soldermask Top")
		(3 "B.Mask" user "Board Geometry/Soldermask Bottom")
		(17 "Dwgs.User" user "User.Drawings")
		(19 "Cmts.User" user "User.Comments")
		(21 "Eco1.User" user "User.Eco1")
		(23 "Eco2.User" user "User.Eco2")
		(25 "Edge.Cuts" user "Board Geometry/Outline")
		(27 "Margin" user)
		(31 "F.CrtYd" user "Package Geometry/Place Bound Top")
		(29 "B.CrtYd" user "Package Geometry/Place Bound Bottom")
		(35 "F.Fab" user "Ref Des/Assembly Top")
		(33 "B.Fab" user "Ref Des/Assembly Bottom")
	)
	(footprint ""
		(layer "F.Cu")
		(at 179.760626 -421.729154 -90)
		(property "Reference" "U192"
			(at 6.665214 1.705864 90)
			(unlocked yes)
			(layer "F.SilkS")
			(effects
				(font
					(size 0.7874 0.5842)
					(thickness 0.1524)
				)
				(justify left)
			)
		)
		(property "Value" ""
			(at 0 0 270)
			(layer "F.Fab")
			(effects
				(font
					(size 1.27 1.27)
				)
			)
		)
		(duplicate_pad_numbers_are_jumpers no)
		(fp_line
			(start -1.3716 1.524)
			(end -1.3716 -1.524)
			(stroke
				(width 0.1524)
				(type default)
			)
			(layer "F.SilkS")
		)
		(fp_line
			(start 1.3716 1.524)
			(end -1.3716 1.524)
			(stroke
				(width 0.1524)
				(type default)
			)
			(layer "F.SilkS")
		)
		(fp_line
			(start 0 -1.016)
			(end 0.508 -1.524)
			(stroke
				(width 0.1524)
				(type default)
			)
			(layer "F.SilkS")
		)
		(fp_line
			(start -1.3716 -1.524)
			(end -0.508 -1.524)
			(stroke
				(width 0.1524)
				(type default)
			)
			(layer "F.SilkS")
		)
		(fp_line
			(start -0.508 -1.524)
			(end 0 -1.016)
			(stroke
				(width 0.1524)
				(type default)
			)
			(layer "F.SilkS")
		)
		(fp_line
			(start 0.508 -1.524)
			(end 1.3716 -1.524)
			(stroke
				(width 0.1524)
				(type default)
			)
			(layer "F.SilkS")
		)
		(fp_line
			(start 1.3716 -1.524)
			(end 1.3716 1.524)
			(stroke
				(width 0.1524)
				(type default)
			)
			(layer "F.SilkS")
		)
		(fp_poly
			(pts
				(xy -1.8669 -1.852676) (xy -2.195068 -1.298956) (xy -2.49174 -1.852676)
			)
			(stroke
				(width 0)
				(type default)
			)
			(fill yes)
			(layer "F.SilkS")
		)
		(fp_line
			(start -1.5494 1.524)
			(end -1.5494 1.0668)
			(stroke
				(width 0.1)
				(type default)
			)
			(layer "F.Fab")
		)
		(fp_line
			(start 1.5494 1.524)
			(end -1.5494 1.524)
			(stroke
				(width 0.1)
				(type default)
			)
			(layer "F.Fab")
		)
		(fp_line
			(start -2.54 1.0668)
			(end -2.54 -1.0668)
			(stroke
				(width 0.1)
				(type default)
			)
			(layer "F.Fab")
		)
		(fp_line
			(start -1.5494 1.0668)
			(end -2.54 1.0668)
			(stroke
				(width 0.1)
				(type default)
			)
			(layer "F.Fab")
		)
		(fp_line
			(start -1.5494 1.0668)
			(end -1.5494 -1.0668)
			(stroke
				(width 0.1)
				(type default)
			)
			(layer "F.Fab")
		)
		(fp_line
			(start 1.5494 1.0668)
			(end 1.5494 1.524)
			(stroke
				(width 0.1)
				(type default)
			)
			(layer "F.Fab")
		)
		(fp_line
			(start 2.54 1.0668)
			(end 1.5494 1.0668)
			(stroke
				(width 0.1)
				(type default)
			)
			(layer "F.Fab")
		)
		(fp_line
			(start -2.54 -1.0668)
			(end -1.5494 -1.0668)
			(stroke
				(width 0.1)
				(type default)
			)
			(layer "F.Fab")
		)
		(fp_line
			(start -1.5494 -1.0668)
			(end -1.5494 -1.524)
			(stroke
				(width 0.1)
				(type default)
			)
			(layer "F.Fab")
		)
		(fp_line
			(start 1.5494 -1.0668)
			(end 1.5494 1.0668)
			(stroke
				(width 0.1)
				(type default)
			)
			(layer "F.Fab")
		)
		(fp_line
			(start 1.5494 -1.0668)
			(end 2.54 -1.0668)
			(stroke
				(width 0.1)
				(type default)
			)
			(layer "F.Fab")
		)
		(fp_line
			(start 2.54 -1.0668)
			(end 2.54 1.0668)
			(stroke
				(width 0.1)
				(type default)
			)
			(layer "F.Fab")
		)
		(fp_line
			(start -1.5494 -1.524)
			(end 1.5494 -1.524)
			(stroke
				(width 0.1)
				(type default)
			)
			(layer "F.Fab")
		)
		(fp_line
			(start 1.5494 -1.524)
			(end 1.5494 -1.0668)
			(stroke
				(width 0.1)
				(type default)
			)
			(layer "F.Fab")
		)
		(fp_poly
			(pts
				(xy -3.60172 -0.719328) (xy -3.60172 -1.344168) (xy -3.048 -1.016)
			)
			(stroke
				(width 0)
				(type default)
			)
			(fill yes)
			(layer "F.Fab")
		)
		(pad "1" smd rect
			(at -2.232406 -0.975106 180)
			(size 0.3556 1.4224)
			(layers "F.Cu" "F.Mask" "F.Paste")
			(net "FM_MB_PDB_SMB9_R_EN")
		)
		(pad "2" smd rect
			(at -2.232406 -0.32512 180)
			(size 0.3556 1.4224)
			(layers "F.Cu" "F.Mask" "F.Paste")
			(net "SMB_FAN_3V3AUX_BUF_SCL")
		)
		(pad "3" smd rect
			(at -2.232406 0.32512 180)
			(size 0.3556 1.4224)
			(layers "F.Cu" "F.Mask" "F.Paste")
			(net "SMB_FAN_3V3AUX_R_SCL")
		)
		(pad "4" smd rect
			(at -2.232406 0.975106 180)
			(size 0.3556 1.4224)
			(layers "F.Cu" "F.Mask" "F.Paste")
			(net "GND")
		)
		(pad "5" smd rect
			(at 2.232406 0.975106 180)
			(size 0.3556 1.4224)
			(layers "F.Cu" "F.Mask" "F.Paste")
			(net "Net_1935")
		)
		(pad "6" smd rect
			(at 2.232406 0.32512 180)
			(size 0.3556 1.4224)
			(layers "F.Cu" "F.Mask" "F.Paste")
			(net "SMB_FAN_3V3AUX_R_SDA")
		)
		(pad "7" smd rect
			(at 2.232406 -0.32512 180)
			(size 0.3556 1.4224)
			(layers "F.Cu" "F.Mask" "F.Paste")
			(net "SMB_FAN_3V3AUX_BUF_SDA")
		)
		(pad "8" smd rect
			(at 2.232406 -0.975106 180)
			(size 0.3556 1.4224)
			(layers "F.Cu" "F.Mask" "F.Paste")
			(net "P3V3_AUX")
		)
	)
	(footprint ""
		(layer "F.Cu")
		(at 151.69388 -22.824948 90)
		(property "Reference" "R2994"
			(at 0 0 90)
			(layer "F.SilkS")
			(hide yes)
			(effects
				(font
					(size 1.27 1.27)
				)
			)
		)
		(property "Value" ""
			(at 0 0 90)
			(layer "F.Fab")
			(effects
				(font
					(size 1.27 1.27)
				)
			)
		)
		(duplicate_pad_numbers_are_jumpers no)
		(fp_line
			(start 0.7874 -0.4064)
			(end 0.7874 0.4064)
			(stroke
				(width 0.1524)
				(type default)
			)
			(layer "F.SilkS")
		)
		(fp_line
			(start -0.7874 -0.4064)
			(end 0.7874 -0.4064)
			(stroke
				(width 0.1524)
				(type default)
			)
			(layer "F.SilkS")
		)
		(fp_line
			(start 0.7874 0.4064)
			(end -0.7874 0.4064)
			(stroke
				(width 0.1524)
				(type default)
			)
			(layer "F.SilkS")
		)
		(fp_line
			(start -0.7874 0.4064)
			(end -0.7874 -0.4064)
			(stroke
				(width 0.1524)
				(type default)
			)
			(layer "F.SilkS")
		)
		(fp_line
			(start -0.12065 -0.305054)
			(end -0.12065 -0.2794)
			(stroke
				(width 0.1)
				(type default)
			)
			(layer "F.Fab")
		)
		(fp_line
			(start -0.67945 -0.305054)
			(end -0.12065 -0.305054)
			(stroke
				(width 0.1)
				(type default)
			)
			(layer "F.Fab")
		)
		(fp_line
			(start 0.67945 -0.3048)
			(end 0.67945 0.3048)
			(stroke
				(width 0.1)
				(type default)
			)
			(layer "F.Fab")
		)
		(fp_line
			(start 0.12065 -0.3048)
			(end 0.67945 -0.3048)
			(stroke
				(width 0.1)
				(type default)
			)
			(layer "F.Fab")
		)
		(fp_line
			(start 0.12065 -0.2794)
			(end 0.12065 -0.3048)
			(stroke
				(width 0.1)
				(type default)
			)
			(layer "F.Fab")
		)
		(fp_line
			(start -0.12065 -0.2794)
			(end 0.12065 -0.2794)
			(stroke
				(width 0.1)
				(type default)
			)
			(layer "F.Fab")
		)
		(fp_line
			(start 0.120396 0.2794)
			(end -0.12065 0.2794)
			(stroke
				(width 0.1)
				(type default)
			)
			(layer "F.Fab")
		)
		(fp_line
			(start -0.12065 0.2794)
			(end -0.12065 0.3048)
			(stroke
				(width 0.1)
				(type default)
			)
			(layer "F.Fab")
		)
		(fp_line
			(start 0.67945 0.3048)
			(end 0.120396 0.3048)
			(stroke
				(width 0.1)
				(type default)
			)
			(layer "F.Fab")
		)
		(fp_line
			(start 0.120396 0.3048)
			(end 0.120396 0.2794)
			(stroke
				(width 0.1)
				(type default)
			)
			(layer "F.Fab")
		)
		(fp_line
			(start -0.12065 0.3048)
			(end -0.67945 0.3048)
			(stroke
				(width 0.1)
				(type default)
			)
			(layer "F.Fab")
		)
		(fp_line
			(start -0.67945 0.3048)
			(end -0.67945 -0.305054)
			(stroke
				(width 0.1)
				(type default)
			)
			(layer "F.Fab")
		)
		(pad "1" smd circle
			(at -0.40005 0 90)
			(size 0 0)
			(layers "F.Cu" "F.Mask" "F.Paste")
			(net "P3V_BAT_R1")
		)
		(pad "2" smd circle
			(at 0.40005 0 90)
			(size 0 0)
			(layers "F.Cu" "F.Mask" "F.Paste")
			(net "P3V_BAT_R")
		)
	)
)
